#ISCELL
  pure_quanta quanta_title_block_c *
  *
#ISCELL
  standard offpage *
  page45_i1
#ISCELL
  standard offpage *
  page45_i10
#ISCELL
  standard offpage *
  page45_i11
#ISCELL
  standard offpage *
  page45_i13
#ISCELL
  standard offpage *
  page45_i14
#ISCELL
  standard offpage *
  page45_i16
#ISCELL
  standard offpage *
  page45_i17
#ISCELL
  standard offpage *
  page45_i18
#ISCELL
  standard offpage *
  page45_i19
#ISCELL
  standard offpage *
  page45_i20
#ISCELL
  standard offpage *
  page45_i21
#ISCELL
  standard offpage *
  page45_i22
#ISCELL
  standard offpage *
  page45_i23
#CELL
  pure_quanta socket4677_azif0045p001c01cs *
  page45_i29
#ISCELL
  standard offpage *
  page45_i32
#ISCELL
  standard offpage *
  page45_i33
#ISCELL
  standard offpage *
  page45_i38
#ISCELL
  standard offpage *
  page45_i39
#ISCELL
  standard offpage *
  page45_i41
#ISCELL
  standard offpage *
  page45_i42
#ISCELL
  standard offpage *
  page45_i43
#ISCELL
  standard offpage *
  page45_i44
#ISCELL
  standard offpage *
  page45_i45
#ISCELL
  standard offpage *
  page45_i46
#ISCELL
  standard offpage *
  page45_i47
#ISCELL
  standard offpage *
  page45_i48
#ISCELL
  standard offpage *
  page45_i49
#ISCELL
  standard offpage *
  page45_i50
#CELL
  pure_quanta q_res *
  page45_i51
#CELL
  pure_quanta q_res *
  page45_i52
#CELL
  pure_quanta q_res *
  page45_i53
#CELL
  pure_quanta q_res *
  page45_i54
#CELL
  pure_quanta q_res *
  page45_i55
#CELL
  pure_quanta q_res *
  page45_i56
#ISCELL
  standard offpage *
  page45_i57
#ISCELL
  standard offpage *
  page45_i58
#ISCELL
  standard offpage *
  page45_i59
#ISCELL
  standard offpage *
  page45_i60
#ISCELL
  standard offpage *
  page45_i61
#ISCELL
  standard offpage *
  page45_i62
#ISCELL
  standard offpage *
  page45_i67
#CELL
  pure_quanta q_res *
  page45_i69
#ISCELL
  standard offpage *
  page45_i7
#CELL
  pure_quanta q_res *
  page45_i70
#ISCELL
  standard offpage *
  page45_i71
#ISCELL
  standard offpage *
  page45_i72
#CELL
  pure_quanta q_res *
  page45_i73
#CELL
  pure_quanta q_res *
  page45_i74
#ISCELL
  logical_power universal_power *
  page45_i75
#ISCELL
  standard offpage *
  page45_i78
#ISCELL
  standard offpage *
  page45_i79
#ISCELL
  standard offpage *
  page45_i8
#CELL
  pure_quanta q_res *
  page45_i81
#CELL
  pure_quanta q_res *
  page45_i82
#ISCELL
  standard offpage *
  page45_i83
#ISCELL
  standard offpage *
  page45_i9
